FILE_TYPE = CONNECTIVITY;
{Allegro Design Entry HDL 16.6-p007 (v16-6-112F) 10/10/2012}
"PAGE_NUMBER" = 108;
0"NC";
1"P3E_CPU0_PE1_PCH_CON_TXN<15:8>";
2"P3E_CPU0_PE1_PCH_CON_TXP<15:8>";
3"P3E_CPU0_PE1_PCH_CON_RXP<15:8>";
4"P3E_CPU0_PE1_PCH_CON_RXN<15:8>";
5"P12V\g";
6"P12V\g";
7"GND\g";
8"P3V3\g";
9"GND\g";
10"P3V3\g";
11"GND\g";
12"P3V3\g";
13"GND\g";
14"P3V3_STBY\g";
15"GND\g";
16"P3V3_STBY\g";
17"P3V3\g";
18"P12V\g";
19"SMB_SLOTX24_STBY_LVC3_SDA_R2";
20"CLK_100M_PCH_SLOTX24_S1_DN";
21"CLK_100M_PCH_SLOTX24_S2_DN";
22"RST_PCIE_RISER1_PERST_R_N";
23"PU_PCH_TLS_ENABLE_STRAP";
24"SMB_SLOTX24_STBY_LVC3_SCL_R2";
25"CLK_100M_PCH_SLOTX24_S0_DN";
26"SMB_SLOTX24_BMC_STBY_LVC3_SDA";
27"FM_SLT_CFG0";
28"CLK_100M_PCH_SLOTX24_S5_DN";
29"SMB_SLOTX24_PCH_STBY_LVC3_SCL";
30"SMB_SLOTX24_PCH_STBY_LVC3_SDA";
31"SMB_SLOTX24_BMC_STBY_LVC3_SCL";
32"SMB_SLOTX24_STBY_LVC3_SCL_R2";
33"RST_PCIE_RISER1_PERST_N";
34"CLK_100M_PCH_SLOTX24_S5_DP";
35"SMB_SLOTX24_STBY_LVC3_SDA_R2";
36"IRQ_OOB_MGMT_RISER_ALERT_N";
37"FM_SLT_CFG1";
38"FM_PWRBRK_SLOT_N";
39"FM_PE_SLOTX24_WAKE_N";
40"SMB_HOST_STBY_LVC3_SDA_R5";
41"SMB_HOST_STBY_LVC3_SCL_R5";
42"FM_PWRBRK_N";
43"CLK_100M_PCH_SLOTX24_S4_DP";
44"P3E_CPU0_PE1_PCH_CON_RXN<15>";
45"P3E_CPU0_PE1_PCH_CON_TXN<11>";
46"P3E_CPU0_PE1_PCH_CON_TXP<10>";
47"P3E_CPU0_PE1_PCH_CON_TXN<9>";
48"P3E_CPU0_PE1_PCH_CON_TXP<9>";
49"P3E_CPU0_PE1_PCH_CON_TXN<8>";
50"P3E_CPU0_PE1_PCH_CON_RXP<15>";
51"P3E_CPU0_PE1_PCH_CON_RXP<14>";
52"P3E_CPU0_PE1_PCH_CON_TXP<8>";
53"P3E_CPU0_PE1_PCH_CON_RXN<8>";
54"P3E_CPU0_PE1_PCH_CON_RXP<10>";
55"P3E_CPU0_PE1_PCH_CON_RXN<9>";
56"P3E_CPU0_PE1_PCH_CON_RXP<9>";
57"P3E_CPU0_PE1_PCH_CON_RXN<13>";
58"P3E_CPU0_PE1_PCH_CON_RXN<14>";
59"P3E_CPU0_PE1_PCH_CON_RXN<12>";
60"P3E_CPU0_PE1_PCH_CON_RXP<12>";
61"P3E_CPU0_PE1_PCH_CON_RXN<11>";
62"P3E_CPU0_PE1_PCH_CON_RXP<11>";
63"P3E_CPU0_PE1_PCH_CON_RXN<10>";
64"P3E_CPU0_PE1_PCH_CON_TXP<13>";
65"P3E_CPU0_PE1_PCH_CON_TXP<11>";
66"P3E_CPU0_PE1_PCH_CON_TXN<10>";
67"P3E_CPU0_PE1_PCH_CON_TXP<14>";
68"P3E_CPU0_PE1_PCH_CON_TXN<14>";
69"TP_SLOTX24_RSVD66";
70"CLK_100M_PCH_SLOTX24_S1_DP";
71"CLK_100M_PCH_SLOTX24_S4_DN";
72"CLK_100M_PCH_SLOTX24_S2_DP";
73"TP_SLOTX24_RSVD63";
74"P3E_CPU0_PE1_PCH_CON_TXN<13>";
75"P3E_CPU0_PE1_PCH_CON_TXN<12>";
76"P3E_CPU0_PE1_PCH_CON_TXP<12>";
77"P3E_CPU0_PE1_PCH_CON_RXP<13>";
78"P3E_CPU0_PE1_PCH_CON_TXP<15>";
79"P3E_CPU0_PE1_PCH_CON_TXN<15>";
80"CLK_100M_PCH_SLOTX24_S3_DN";
81"CLK_100M_PCH_SLOTX24_S3_DP";
82"CLK_100M_PCH_SLOTX24_S0_DP";
%"CAP_A"
"1","(-3275,675)","0","dev_discrete","I1";
;
PACK_TYPE"0402V"
MATERIAL"X7R"
VOLTAGE"16V"
TOLERANCE"10%"
VALUE"0.1UF"
LOCATION"C2U20"
PART_NUMBER"A36096-030"
CDS_LIB"dev_discrete"
CDS_SEC"1"
CDS_LOCATION"C2U20"
SEC"1"
SEC_TYPE"0402V"
ROOM"IO_SLOT";
"B"
$PN"2"11;
"A"
$PN"1"18;
%"P12V"
"1","(1375,4675)","0","mstr_symbols","I165";
;
HDL_POWER"P12V"
SIZE"1B"
CDS_LIB"mstr_symbols"
BODY_TYPE"PLUMBING"
VOLTAGE"+12.";
"G\NAC"5;
%"P12V"
"1","(-350,4725)","0","mstr_symbols","I167";
;
HDL_POWER"P12V"
BODY_TYPE"PLUMBING"
CDS_LIB"mstr_symbols"
SIZE"1B"
VOLTAGE"+12.";
"G\NAC"6;
%"GND"
"1","(-100,1600)","0","mstr_symbols","I168";
;
HDL_POWER"GND"
BODY_TYPE"PLUMBING"
SIZE"1B"
CDS_LIB"mstr_symbols"
VOLTAGE"0";
"A\NAC"7;
%"P3V3"
"1","(-525,4100)","0","mstr_symbols","I172";
;
SIZE"1B"
VOLTAGE"3.3V"
CDS_LIB"mstr_symbols"
BODY_TYPE"PLUMBING"
HDL_POWER"P3V3";
"G\NAC"8;
%"RES"
"1","(-1100,3625)","0","mstr_discrete","I173";
;
CDS_SEC"1"
WATTAGE"1/16W"
TOLERANCE"5%"
LOCATION"R2U37"
PART_NUMBER"G21497-005"
MATERIAL"CHIP"
PACK_TYPE"0402"
VALUE"0.0"
SEC_TYPE"0402"
SEC"1"
ROOM"IO_SLOT"
CDS_LIB"mstr_discrete"
CDS_LOCATION"R2U37";
"B"
$PN"2"22;
"A"
$PN"1"33;
%"CAP_A"
"1","(-2875,650)","0","dev_discrete","I2";
;
PACK_TYPE"0402V"
MATERIAL"X7R"
VOLTAGE"16V"
TOLERANCE"10%"
VALUE"0.1UF"
LOCATION"C2U24"
PART_NUMBER"A36096-030"
CDS_LIB"dev_discrete"
CDS_LOCATION"C2U24"
SEC"1"
SEC_TYPE"0402V"
CDS_SEC"1"
ROOM"IO_SLOT";
"B"
$PN"2"11;
"A"
$PN"1"18;
%"GND"
"1","(1050,1600)","0","mstr_symbols","I236";
;
VOLTAGE"0"
SIZE"1B"
CDS_LIB"mstr_symbols"
HDL_POWER"GND"
BODY_TYPE"PLUMBING";
"A\NAC"9;
%"P3V3"
"1","(1600,4675)","0","mstr_symbols","I238";
;
HDL_POWER"P3V3"
BODY_TYPE"PLUMBING"
CDS_LIB"mstr_symbols"
SIZE"1B"
VOLTAGE"3.3V";
"G\NAC"10;
%"GND"
"1","(-2875,300)","0","mstr_symbols","I250";
;
BODY_TYPE"PLUMBING"
CDS_LIB"mstr_symbols"
VOLTAGE"0"
HDL_POWER"GND"
SIZE"1B";
"A\NAC"11;
%"P3V3"
"1","(-3275,1650)","0","mstr_symbols","I251";
;
HDL_POWER"P3V3"
VOLTAGE"3.3V"
BODY_TYPE"PLUMBING"
CDS_LIB"mstr_symbols"
SIZE"1B";
"G\NAC"12;
%"GND"
"1","(-2875,975)","0","mstr_symbols","I252";
;
BODY_TYPE"PLUMBING"
CDS_LIB"mstr_symbols"
VOLTAGE"0"
SIZE"1B"
HDL_POWER"GND";
"A\NAC"13;
%"SCONN200_H68296001"
"1","(500,3075)","0","mstr_sconn","I258";
;
CDS_SEC"1"
PART_NUMBER"H68296-001"
LOCATION"J8G1"
MATERIAL"CONN"
CDS_LIB"mstr_sconn"
CDS_LMAN_SYM_OUTLINE"-250,1350,250,-1350"
CDS_LOCATION"J8G1"
PACK_TYPE"SM"
ROOM"IO_SLOT"
SEC"1"
SEC_TYPE"SM";
"MH2"
$PN"MH2"9;
"IO98"
$PN"98"9;
"IO96"
$PN"96"56;
"IO94"
$PN"94"55;
"IO92"
$PN"92"9;
"IO90"
$PN"90"54;
"IO88"
$PN"88"63;
"MH1"
$PN"MH1"7;
"IO65"
$PN"65"7;
"IO67"
$PN"67"74;
"IO69"
$PN"69"64;
"IO100"
$PN"100"53;
"IO73"
$PN"73"75;
"IO99"
$PN"99"52;
"IO78"
$PN"78"60;
"IO74"
$PN"74"9;
"IO72"
$PN"72"77;
"IO71"
$PN"71"7;
"IO70"
$PN"70"57;
"IO68"
$PN"68"9;
"IO66"
$PN"66"69;
"IO64"
$PN"64"9;
"IO63"
$PN"63"73;
"IO62"
$PN"62"51;
"IO61"
$PN"61"7;
"IO60"
$PN"60"58;
"IO59"
$PN"59"68;
"IO58"
$PN"58"9;
"IO57"
$PN"57"67;
"IO56"
$PN"56"50;
"IO55"
$PN"55"7;
"IO54"
$PN"54"44;
"IO53"
$PN"53"78;
"IO52"
$PN"52"9;
"IO50"
$PN"50"21;
"IO48"
$PN"48"72;
"IO46"
$PN"46"9;
"IO45"
$PN"45"81;
"IO44"
$PN"44"20;
"IO43"
$PN"43"7;
"IO41"
$PN"41"25;
"IO40"
$PN"40"9;
"IO39"
$PN"39"82;
"IO37"
$PN"37"7;
"IO36"
$PN"36"43;
"IO35"
$PN"35"28;
"IO34"
$PN"34"9;
"IO33"
$PN"33"34;
"IO32"
$PN"32"41;
"IO31"
$PN"31"7;
"IO30"
$PN"30"40;
"IO29"
$PN"29"22;
"IO28"
$PN"28"39;
"IO27"
$PN"27"23;
"IO25"
$PN"25"14;
"IO23"
$PN"23"8;
"IO21"
$PN"21"8;
"IO19"
$PN"19"27;
"IO16"
$PN"16"36;
"IO14"
$PN"14"9;
"IO12"
$PN"12"5;
"IO10"
$PN"10"5;
"IO8"
$PN"8"5;
"IO6"
$PN"6"5;
"IO4"
$PN"4"5;
"IO2"
$PN"2"5;
"IO9"
$PN"9"6;
"IO38"
$PN"38"71;
"IO18"
$PN"18"37;
"IO20"
$PN"20"38;
"IO22"
$PN"22"10;
"IO24"
$PN"24"10;
"IO26"
$PN"26"9;
"IO7"
$PN"7"6;
"IO5"
$PN"5"6;
"IO3"
$PN"3"6;
"IO1"
$PN"1"6;
"IO76"
$PN"76"59;
"IO80"
$PN"80"9;
"IO75"
$PN"75"76;
"IO82"
$PN"82"61;
"IO84"
$PN"84"62;
"IO86"
$PN"86"9;
"IO77"
$PN"77"7;
"IO95"
$PN"95"7;
"IO97"
$PN"97"49;
"IO93"
$PN"93"48;
"IO91"
$PN"91"47;
"IO89"
$PN"89"7;
"IO87"
$PN"87"46;
"IO85"
$PN"85"66;
"IO83"
$PN"83"7;
"IO81"
$PN"81"65;
"IO79"
$PN"79"45;
"IO51"
$PN"51"79;
"IO49"
$PN"49"7;
"IO47"
$PN"47"80;
"IO42"
$PN"42"70;
"IO15"
$PN"15"19;
"IO17"
$PN"17"32;
"IO13"
$PN"13"7;
"IO11"
$PN"11"6;
%"P3V3_STBY"
"1","(-25,4625)","0","mstr_symbols","I262";
;
HDL_POWER"P3V3_STBY"
BODY_TYPE"PLUMBING"
VOLTAGE"3.3V"
CDS_LIB"mstr_symbols"
SIZE"1B";
"G\NAC"14;
%"TAP"
"1","(-550,3075)","2","mstr_standard","I271";
;
CDS_LIB"mstr_standard"
BODY_TYPE"PLUMBING"
HDL_TAP"TRUE";
"B \NAC \NWC"1;
"S \NAC"
BN"15"79;
%"TAP"
"1","(-750,3025)","2","mstr_standard","I272";
;
BODY_TYPE"PLUMBING"
CDS_LIB"mstr_standard"
HDL_TAP"TRUE";
"B \NAC \NWC"2;
"S \NAC"
BN"15"78;
%"TAP"
"1","(-750,2925)","2","mstr_standard","I273";
;
HDL_TAP"TRUE"
BODY_TYPE"PLUMBING"
CDS_LIB"mstr_standard";
"B \NAC \NWC"2;
"S \NAC"
BN"14"67;
%"TAP"
"1","(-550,2875)","2","mstr_standard","I274";
;
HDL_TAP"TRUE"
BODY_TYPE"PLUMBING"
CDS_LIB"mstr_standard";
"B \NAC \NWC"1;
"S \NAC"
BN"14"68;
%"TAP"
"1","(-750,2625)","2","mstr_standard","I275";
;
HDL_TAP"TRUE"
BODY_TYPE"PLUMBING"
CDS_LIB"mstr_standard";
"B \NAC \NWC"2;
"S \NAC"
BN"13"64;
%"TAP"
"1","(-550,2675)","2","mstr_standard","I276";
;
HDL_TAP"TRUE"
BODY_TYPE"PLUMBING"
CDS_LIB"mstr_standard";
"B \NAC \NWC"1;
"S \NAC"
BN"13"74;
%"TAP"
"1","(-750,2475)","2","mstr_standard","I277";
;
BODY_TYPE"PLUMBING"
CDS_LIB"mstr_standard"
HDL_TAP"TRUE";
"B \NAC \NWC"2;
"S \NAC"
BN"12"76;
%"TAP"
"1","(-550,2525)","2","mstr_standard","I278";
;
HDL_TAP"TRUE"
CDS_LIB"mstr_standard"
BODY_TYPE"PLUMBING";
"B \NAC \NWC"1;
"S \NAC"
BN"12"75;
%"TAP"
"1","(-750,2325)","2","mstr_standard","I279";
;
HDL_TAP"TRUE"
BODY_TYPE"PLUMBING"
CDS_LIB"mstr_standard";
"B \NAC \NWC"2;
"S \NAC"
BN"11"65;
%"TAP"
"1","(-550,2375)","2","mstr_standard","I280";
;
HDL_TAP"TRUE"
BODY_TYPE"PLUMBING"
CDS_LIB"mstr_standard";
"B \NAC \NWC"1;
"S \NAC"
BN"11"45;
%"TAP"
"1","(-750,2175)","2","mstr_standard","I281";
;
HDL_TAP"TRUE"
BODY_TYPE"PLUMBING"
CDS_LIB"mstr_standard";
"B \NAC \NWC"2;
"S \NAC"
BN"10"46;
%"TAP"
"1","(-550,2225)","2","mstr_standard","I282";
;
HDL_TAP"TRUE"
CDS_LIB"mstr_standard"
BODY_TYPE"PLUMBING";
"B \NAC \NWC"1;
"S \NAC"
BN"10"66;
%"TAP"
"1","(-750,2025)","2","mstr_standard","I283";
;
HDL_TAP"TRUE"
CDS_LIB"mstr_standard"
BODY_TYPE"PLUMBING";
"B \NAC \NWC"2;
"S \NAC"
BN"9"48;
%"TAP"
"1","(-550,2075)","2","mstr_standard","I284";
;
HDL_TAP"TRUE"
BODY_TYPE"PLUMBING"
CDS_LIB"mstr_standard";
"B \NAC \NWC"1;
"S \NAC"
BN"9"47;
%"TAP"
"1","(-750,1875)","2","mstr_standard","I285";
;
HDL_TAP"TRUE"
BODY_TYPE"PLUMBING"
CDS_LIB"mstr_standard";
"B \NAC \NWC"2;
"S \NAC"
BN"8"52;
%"TAP"
"1","(-550,1925)","2","mstr_standard","I286";
;
HDL_TAP"TRUE"
BODY_TYPE"PLUMBING"
CDS_LIB"mstr_standard";
"B \NAC \NWC"1;
"S \NAC"
BN"8"49;
%"TAP"
"1","(1350,2975)","0","mstr_standard","I295";
;
CDS_LIB"mstr_standard"
HDL_TAP"TRUE"
BODY_TYPE"PLUMBING";
"B \NAC \NWC"3;
"S \NAC"
BN"15"50;
%"TAP"
"1","(1500,3025)","0","mstr_standard","I296";
;
CDS_LIB"mstr_standard"
BODY_TYPE"PLUMBING"
HDL_TAP"TRUE";
"B \NAC \NWC"4;
"S \NAC"
BN"15"44;
%"TAP"
"1","(1500,2875)","0","mstr_standard","I297";
;
HDL_TAP"TRUE"
BODY_TYPE"PLUMBING"
CDS_LIB"mstr_standard";
"B \NAC \NWC"4;
"S \NAC"
BN"14"58;
%"TAP"
"1","(1350,2825)","0","mstr_standard","I298";
;
CDS_LIB"mstr_standard"
BODY_TYPE"PLUMBING"
HDL_TAP"TRUE";
"B \NAC \NWC"3;
"S \NAC"
BN"14"51;
%"TAP"
"1","(1500,2625)","0","mstr_standard","I299";
;
CDS_LIB"mstr_standard"
BODY_TYPE"PLUMBING"
HDL_TAP"TRUE";
"B \NAC \NWC"4;
"S \NAC"
BN"13"57;
%"TAP"
"1","(1350,2575)","0","mstr_standard","I300";
;
CDS_LIB"mstr_standard"
BODY_TYPE"PLUMBING"
HDL_TAP"TRUE";
"B \NAC \NWC"3;
"S \NAC"
BN"13"77;
%"TAP"
"1","(1500,2475)","0","mstr_standard","I301";
;
BODY_TYPE"PLUMBING"
CDS_LIB"mstr_standard"
HDL_TAP"TRUE";
"B \NAC \NWC"4;
"S \NAC"
BN"12"59;
%"TAP"
"1","(1350,2425)","0","mstr_standard","I302";
;
HDL_TAP"TRUE"
CDS_LIB"mstr_standard"
BODY_TYPE"PLUMBING";
"B \NAC \NWC"3;
"S \NAC"
BN"12"60;
%"TAP"
"1","(1500,2325)","0","mstr_standard","I303";
;
CDS_LIB"mstr_standard"
BODY_TYPE"PLUMBING"
HDL_TAP"TRUE";
"B \NAC \NWC"4;
"S \NAC"
BN"11"61;
%"TAP"
"1","(1350,2275)","0","mstr_standard","I304";
;
BODY_TYPE"PLUMBING"
CDS_LIB"mstr_standard"
HDL_TAP"TRUE";
"B \NAC \NWC"3;
"S \NAC"
BN"11"62;
%"TAP"
"1","(1500,2175)","0","mstr_standard","I305";
;
CDS_LIB"mstr_standard"
BODY_TYPE"PLUMBING"
HDL_TAP"TRUE";
"B \NAC \NWC"4;
"S \NAC"
BN"10"63;
%"TAP"
"1","(1350,2125)","0","mstr_standard","I306";
;
CDS_LIB"mstr_standard"
BODY_TYPE"PLUMBING"
HDL_TAP"TRUE";
"B \NAC \NWC"3;
"S \NAC"
BN"10"54;
%"CAP_A"
"1","(-1950,1350)","0","dev_discrete","I315";
;
MATERIAL"X7R"
TOLERANCE"10%"
VOLTAGE"16V"
PART_NUMBER"A36096-030"
VALUE"0.1UF"
PACK_TYPE"0402V"
LOCATION"C2U23"
CDS_LIB"dev_discrete"
CDS_LOCATION"C2U23"
CDS_SEC"1"
SEC"1"
SEC_TYPE"0402V"
ROOM"IO_SLOT";
"B"
$PN"2"15;
"A"
$PN"1"16;
%"GND"
"1","(-1950,950)","0","mstr_symbols","I316";
;
BODY_TYPE"PLUMBING"
CDS_LIB"mstr_symbols"
SIZE"1B"
VOLTAGE"0"
HDL_POWER"GND";
"A\NAC"15;
%"CAP_A"
"1","(-2350,1375)","0","dev_discrete","I318";
;
LOCATION"C2U22"
VALUE"0.1UF"
MATERIAL"X7R"
TOLERANCE"10%"
VOLTAGE"16V"
PACK_TYPE"0402V"
PART_NUMBER"A36096-030"
CDS_LIB"dev_discrete"
CDS_LOCATION"C2U22"
CDS_SEC"1"
ROOM"IO_SLOT"
SEC_TYPE"0402V"
SEC"1";
"B"
$PN"2"15;
"A"
$PN"1"16;
%"P3V3_STBY"
"1","(-2350,1625)","0","mstr_symbols","I319";
;
HDL_POWER"P3V3_STBY"
VOLTAGE"3.3V"
BODY_TYPE"PLUMBING"
SIZE"1B"
CDS_LIB"mstr_symbols";
"G\NAC"16;
%"RES"
"1","(-2275,4500)","0","mstr_discrete","I330";
;
VALUE"20.0"
LOCATION"R2U31"
TOLERANCE"1%"
MATERIAL"CHIP"
PART_NUMBER"G21796-173"
WATTAGE"1/16W"
PACK_TYPE"0402"
BOM_COST"SM_CONTROLLER"
CDS_SEC"1"
$SEC"1"
ROOM"SMBUS"
SKU"B"
CDS_LIB"mstr_discrete"
CDS_LOCATION"R2U31";
"B"
$PN"2"35;
"A"
$PN"1"26;
%"RES"
"1","(-2275,4250)","0","mstr_discrete","I339";
;
VALUE"20.0"
LOCATION"R2U32"
TOLERANCE"1%"
PACK_TYPE"0402"
WATTAGE"1/16W"
MATERIAL"CHIP"
PART_NUMBER"G21796-173"
BOM_COST"SM_CONTROLLER"
ROOM"SMBUS"
SKU"B"
CDS_SEC"1"
$SEC"1"
CDS_LIB"mstr_discrete"
CDS_LOCATION"R2U32";
"B"
$PN"2"24;
"A"
$PN"1"31;
%"RES"
"1","(2600,3775)","0","mstr_discrete","I341";
;
CDS_SEC"1"
CDS_LOCATION"R7E22"
LOCATION"R7E22"
TOLERANCE"5%"
PART_NUMBER"G21497-005"
PACK_TYPE"0402"
MATERIAL"CHIP"
VALUE"0.0"
WATTAGE"1/16W"
CDS_LIB"mstr_discrete"
ROOM"IO_SLOT"
SEC"1"
SEC_TYPE"0402";
"B"
$PN"2"38;
"A"
$PN"1"42;
%"RES"
"2","(2350,4200)","0","mstr_discrete","I343";
;
CDS_SEC"1"
CDS_LOCATION"R7E21"
PACK_TYPE"0402"
MATERIAL"CHIP"
PART_NUMBER"G21796-072"
WATTAGE"1/16W"
TOLERANCE"1%"
VALUE"4.75K"
LOCATION"R7E21"
CDS_LIB"mstr_discrete"
ROOM"IO_SLOT"
SEC"1"
SEC_TYPE"0402";
"A"
$PN"1"17;
"B"
$PN"2"42;
%"P3V3"
"1","(2350,4400)","0","mstr_symbols","I344";
;
HDL_POWER"P3V3"
BODY_TYPE"PLUMBING"
SIZE"1B"
CDS_LIB"mstr_symbols"
VOLTAGE"3.3V";
"G\NAC"17;
%"TAP"
"1","(1500,1875)","0","mstr_standard","I345";
;
HDL_TAP"TRUE"
BODY_TYPE"PLUMBING"
CDS_LIB"mstr_standard";
"B \NAC \NWC"4;
"S \NAC"
BN"8"53;
%"TAP"
"1","(1500,2025)","0","mstr_standard","I346";
;
CDS_LIB"mstr_standard"
HDL_TAP"TRUE"
BODY_TYPE"PLUMBING";
"B \NAC \NWC"4;
"S \NAC"
BN"9"55;
%"TAP"
"1","(1350,1975)","0","mstr_standard","I347";
;
HDL_TAP"TRUE"
CDS_LIB"mstr_standard"
BODY_TYPE"PLUMBING";
"B \NAC \NWC"3;
"S \NAC"
BN"9"56;
%"RES"
"1","(-2275,4625)","0","mstr_discrete","I350";
;
VALUE"20.0"
WATTAGE"1/16W"
LOCATION"R2U35"
TOLERANCE"1%"
PACK_TYPE"0402"
MATERIAL"EMPTY"
PART_NUMBER"G21796-173"
CDS_LIB"mstr_discrete"
$SEC"1"
CDS_SEC"1"
ROOM"SMBUS"
SKU"A"
BOM_COST"SM_CONTROLLER"
CDS_LOCATION"R2U35";
"B"
$PN"2"35;
"A"
$PN"1"30;
%"RES"
"1","(-2275,4375)","0","mstr_discrete","I351";
;
VALUE"20.0"
TOLERANCE"1%"
LOCATION"R2U36"
PACK_TYPE"0402"
WATTAGE"1/16W"
PART_NUMBER"G21796-173"
MATERIAL"EMPTY"
BOM_COST"SM_CONTROLLER"
SKU"A"
ROOM"SMBUS"
CDS_SEC"1"
$SEC"1"
CDS_LIB"mstr_discrete"
CDS_LOCATION"R2U36";
"B"
$PN"2"24;
"A"
$PN"1"29;
%"P12V"
"1","(-3275,925)","0","mstr_symbols","I4";
;
HDL_POWER"P12V"
BODY_TYPE"PLUMBING"
VOLTAGE"+12."
SIZE"1B"
CDS_LIB"mstr_symbols";
"G\NAC"18;
%"CAP_A"
"1","(-3275,1400)","0","dev_discrete","I5";
;
PACK_TYPE"0402V"
VALUE"0.1UF"
LOCATION"C2U21"
TOLERANCE"10%"
VOLTAGE"16V"
MATERIAL"X7R"
PART_NUMBER"A36096-030"
CDS_LOCATION"C2U21"
CDS_LIB"dev_discrete"
ROOM"IO_SLOT"
CDS_SEC"1"
SEC"1"
SEC_TYPE"0402V";
"B"
$PN"2"13;
"A"
$PN"1"12;
%"CAP_A"
"1","(-2875,1375)","0","dev_discrete","I7";
;
MATERIAL"X7R"
TOLERANCE"10%"
PACK_TYPE"0402V"
PART_NUMBER"A36096-030"
VALUE"0.1UF"
VOLTAGE"16V"
LOCATION"C2U25"
CDS_LIB"dev_discrete"
CDS_LOCATION"C2U25"
CDS_SEC"1"
ROOM"IO_SLOT"
SEC_TYPE"0402V"
SEC"1";
"B"
$PN"2"13;
"A"
$PN"1"12;
END.
